# BASEBOARD_FAB2 (Tioga Pass) — schematic netlist excerpt (pin names and nets, part order shuffled) for the footprints in the layout excerpt that follows; sources: Cadence DE-HDL packaged netlist, KiCad conversion of Wiwynn_Tioga_Pass_MB.brd

RT43  1R3F-GP  1%  pkg RCL_GP  page 236 : \1\ = VR_PVNN_PCH_PH1_PHASE_SW_RC ; \2\ = GND
R1T37  RES  0.0 5% CHIP  pkg 0402  page 93 : A = FM_CPU1_PROCHOT_LVT3_N ; B = FM_CPU1_PROCHOT_LVT3_BMC_N
R1B21  RES  4.75K 1% CHIP  pkg 0402  page 161 : A = P3V3_STBY ; B = FAN_TACH2

(kicad_pcb
	(version 20260206)
	(generator "pcbnew")
	(generator_version "10.0")
	(general
		(thickness 1.6)
		(legacy_teardrops no)
	)
	(paper "A4")
	(title_block
		(title "Wiwynn_Tioga_Pass_MB.brd")
		(comment 1 "Tioga Pass / footprints 918-920 of 4770")
	)
	(layers
		(0 "F.Cu" signal "TOP")
		(4 "In1.Cu" signal "L2GND")
		(6 "In2.Cu" signal "L3")
		(8 "In3.Cu" signal "L4GND")
		(10 "In4.Cu" signal "L5")
		(12 "In5.Cu" signal "L6GND")
		(14 "In6.Cu" signal "L7VCC")
		(16 "In7.Cu" signal "L8VCC")
		(18 "In8.Cu" signal "L9GND")
		(20 "In9.Cu" signal "L10")
		(22 "In10.Cu" signal "L11GND")
		(24 "In11.Cu" signal "L12")
		(26 "In12.Cu" signal "L13GND")
		(2 "B.Cu" signal "BOTTOM")
		(9 "F.Adhes" user "F.Adhesive")
		(11 "B.Adhes" user "B.Adhesive")
		(13 "F.Paste" user "Package Geometry/Pastemask Top")
		(15 "B.Paste" user "Package Geometry/Pastemask Bottom")
		(5 "F.SilkS" user "Ref Des/Silkscreen Top")
		(7 "B.SilkS" user "Ref Des/Silkscreen Bottom")
		(1 "F.Mask" user "Board Geometry/Soldermask Top")
		(3 "B.Mask" user "Board Geometry/Soldermask Bottom")
		(17 "Dwgs.User" user "User.Drawings")
		(19 "Cmts.User" user "User.Comments")
		(21 "Eco1.User" user "User.Eco1")
		(23 "Eco2.User" user "User.Eco2")
		(25 "Edge.Cuts" user "Board Geometry/Outline")
		(27 "Margin" user)
		(31 "F.CrtYd" user "Package Geometry/Place Bound Top")
		(29 "B.CrtYd" user "Package Geometry/Place Bound Bottom")
		(35 "F.Fab" user "Ref Des/Assembly Top")
		(33 "B.Fab" user "Ref Des/Assembly Bottom")
	)
	(footprint ""
		(layer "F.Cu")
		(at 372.550182 -149.543262 180)
		(property "Reference" "RT43"
			(at 0 0 180)
			(layer "F.SilkS")
			(hide yes)
			(effects
				(font
					(size 1.27 1.27)
				)
			)
		)
		(property "Value" "*"
			(at -0.0254 -2.6289 180)
			(unlocked yes)
			(layer "F.Fab")
			(hide yes)
			(effects
				(font
					(size 1.27 1.016)
					(thickness 0.1524)
				)
			)
		)
		(property "Device Type" "1R3F-GP_RCL_GP-1R3F-GP,64.1R00A"
			(at -0.0254 -4.1529 180)
			(unlocked yes)
			(layer "F.Fab")
			(hide yes)
			(effects
				(font
					(size 1.27 1.016)
					(thickness 0.1524)
				)
			)
		)
		(duplicate_pad_numbers_are_jumpers no)
		(fp_line
			(start 0.2032 0)
			(end 0.4826 0)
			(stroke
				(width 0.2032)
				(type default)
			)
			(layer "F.SilkS")
		)
		(fp_line
			(start -0.4826 0)
			(end -0.2032 0)
			(stroke
				(width 0.2032)
				(type default)
			)
			(layer "F.SilkS")
		)
		(fp_rect
			(start -0.5842 1.3335)
			(end 0.5842 -1.3335)
			(stroke
				(width 0)
				(type default)
			)
			(fill no)
			(layer "F.CrtYd")
		)
		(fp_rect
			(start -0.5842 1.3335)
			(end 0.5842 -1.3335)
			(stroke
				(width 0)
				(type default)
			)
			(fill no)
			(layer "F.Fab")
		)
		(pad "1" smd custom
			(at 0 -0.762 180)
			(size 0.2159 0.2159)
			(layers "F.Cu" "F.Mask" "F.Paste")
			(net "VR_PVNN_PCH_PH1_PHASE_SW_RC")
			(options
				(clearance outline)
				(anchor circle)
			)
			(primitives
				(gr_poly
					(pts
						(arc
							(start -0.3302 -0.4318)
							(mid -0.402042 -0.402042)
							(end -0.4318 -0.3302)
						)
						(arc
							(start -0.4318 0.3302)
							(mid -0.402042 0.402042)
							(end -0.3302 0.4318)
						)
						(arc
							(start 0.3302 0.4318)
							(mid 0.402042 0.402042)
							(end 0.4318 0.3302)
						)
						(arc
							(start 0.4318 -0.3302)
							(mid 0.402042 -0.402042)
							(end 0.3302 -0.4318)
						)
					)
					(width 0)
					(fill yes)
				)
			)
		)
		(pad "2" smd custom
			(at 0 0.762 180)
			(size 0.2159 0.2159)
			(layers "F.Cu" "F.Mask" "F.Paste")
			(net "GND")
			(options
				(clearance outline)
				(anchor circle)
			)
			(primitives
				(gr_poly
					(pts
						(arc
							(start -0.3302 -0.4318)
							(mid -0.402042 -0.402042)
							(end -0.4318 -0.3302)
						)
						(arc
							(start -0.4318 0.3302)
							(mid -0.402042 0.402042)
							(end -0.3302 0.4318)
						)
						(arc
							(start 0.3302 0.4318)
							(mid 0.402042 0.402042)
							(end 0.4318 0.3302)
						)
						(arc
							(start 0.4318 -0.3302)
							(mid 0.402042 -0.402042)
							(end 0.3302 -0.4318)
						)
					)
					(width 0)
					(fill yes)
				)
			)
		)
	)
	(footprint ""
		(layer "F.Cu")
		(at 402.590254 -40.985948 90)
		(property "Reference" "R1T37"
			(at 0 0 90)
			(layer "F.SilkS")
			(hide yes)
			(effects
				(font
					(size 1.27 1.27)
				)
			)
		)
		(property "Value" ""
			(at 0 0 90)
			(layer "F.Fab")
			(effects
				(font
					(size 1.27 1.27)
				)
			)
		)
		(duplicate_pad_numbers_are_jumpers no)
		(fp_poly
			(pts
				(xy -0.2794 -0.1016) (xy 0.2794 -0.1016) (xy 0.2794 0.9906) (xy -0.2794 0.9906)
			)
			(stroke
				(width 0)
				(type default)
			)
			(fill no)
			(layer "F.CrtYd")
		)
		(fp_line
			(start 0.2794 -0.1016)
			(end -0.2794 -0.1016)
			(stroke
				(width 0.1)
				(type default)
			)
			(layer "F.Fab")
		)
		(fp_line
			(start -0.2794 -0.1016)
			(end -0.2794 0.9906)
			(stroke
				(width 0.1)
				(type default)
			)
			(layer "F.Fab")
		)
		(fp_line
			(start 0.2794 0.9906)
			(end 0.2794 -0.1016)
			(stroke
				(width 0.1)
				(type default)
			)
			(layer "F.Fab")
		)
		(fp_line
			(start -0.2794 0.9906)
			(end 0.2794 0.9906)
			(stroke
				(width 0.1)
				(type default)
			)
			(layer "F.Fab")
		)
		(pad "1" smd rect
			(at 0 0 90)
			(size 0.508 0.508)
			(layers "F.Cu" "F.Mask" "F.Paste")
			(net "FM_CPU1_PROCHOT_LVT3_N")
		)
		(pad "2" smd rect
			(at 0 0.889 90)
			(size 0.508 0.508)
			(layers "F.Cu" "F.Mask" "F.Paste")
			(net "FM_CPU1_PROCHOT_LVT3_BMC_N")
		)
		(zone
			(layer "F.Cu")
			(hatch none 0.5)
			(connect_pads
				(clearance 0)
			)
			(min_thickness 0.25)
			(keepout
				(tracks allowed)
				(vias not_allowed)
				(pads allowed)
				(copperpour not_allowed)
				(footprints allowed)
			)
			(placement
				(enabled no)
				(sheetname "")
			)
			(fill
				(thermal_gap 0.5)
				(thermal_bridge_width 0.5)
				(island_removal_mode 0)
			)
			(polygon
				(pts
					(xy 402.844254 -40.731948) (xy 402.844254 -41.239948) (xy 403.225254 -41.239948) (xy 403.225254 -40.731948)
				)
			)
		)
		(zone
			(layer "F.Cu")
			(hatch none 0.5)
			(connect_pads
				(clearance 0)
			)
			(min_thickness 0.25)
			(keepout
				(tracks not_allowed)
				(vias allowed)
				(pads allowed)
				(copperpour not_allowed)
				(footprints allowed)
			)
			(placement
				(enabled no)
				(sheetname "")
			)
			(fill
				(thermal_gap 0.5)
				(thermal_bridge_width 0.5)
				(island_removal_mode 0)
			)
			(polygon
				(pts
					(xy 403.225254 -40.731948) (xy 403.225254 -41.239948) (xy 402.844254 -41.239948) (xy 402.844254 -40.731948)
				)
			)
		)
	)
	(footprint ""
		(layer "F.Cu")
		(at 18.071592 -117.145054 90)
		(property "Reference" "R1B21"
			(at 0 0 90)
			(layer "F.SilkS")
			(hide yes)
			(effects
				(font
					(size 1.27 1.27)
				)
			)
		)
		(property "Value" ""
			(at 0 0 90)
			(layer "F.Fab")
			(effects
				(font
					(size 1.27 1.27)
				)
			)
		)
		(duplicate_pad_numbers_are_jumpers no)
		(fp_rect
			(start -0.2794 0.9906)
			(end 0.2794 -0.1016)
			(stroke
				(width 0)
				(type default)
			)
			(fill no)
			(layer "F.CrtYd")
		)
		(fp_line
			(start 0.2794 -0.1016)
			(end -0.2794 -0.1016)
			(stroke
				(width 0.1)
				(type default)
			)
			(layer "F.Fab")
		)
		(fp_line
			(start -0.2794 -0.1016)
			(end -0.2794 0.9906)
			(stroke
				(width 0.1)
				(type default)
			)
			(layer "F.Fab")
		)
		(fp_line
			(start 0.2794 0.9906)
			(end 0.2794 -0.1016)
			(stroke
				(width 0.1)
				(type default)
			)
			(layer "F.Fab")
		)
		(fp_line
			(start -0.2794 0.9906)
			(end 0.2794 0.9906)
			(stroke
				(width 0.1)
				(type default)
			)
			(layer "F.Fab")
		)
		(pad "1" smd rect
			(at 0 0 90)
			(size 0.508 0.508)
			(layers "F.Cu" "F.Mask" "F.Paste")
			(net "P3V3_STBY")
		)
		(pad "2" smd rect
			(at 0 0.889 90)
			(size 0.508 0.508)
			(layers "F.Cu" "F.Mask" "F.Paste")
			(net "FAN_TACH2")
		)
		(zone
			(layer "F.Cu")
			(hatch none 0.5)
			(connect_pads
				(clearance 0)
			)
			(min_thickness 0.25)
			(keepout
				(tracks allowed)
				(vias not_allowed)
				(pads allowed)
				(copperpour not_allowed)
				(footprints allowed)
			)
			(placement
				(enabled no)
				(sheetname "")
			)
			(fill
				(thermal_gap 0.5)
				(thermal_bridge_width 0.5)
				(island_removal_mode 0)
			)
			(polygon
				(pts
					(xy 18.706592 -116.891054) (xy 18.706592 -117.399054) (xy 18.325592 -117.399054) (xy 18.325592 -116.891054)
				)
			)
		)
		(zone
			(layer "F.Cu")
			(hatch none 0.5)
			(connect_pads
				(clearance 0)
			)
			(min_thickness 0.25)
			(keepout
				(tracks not_allowed)
				(vias allowed)
				(pads allowed)
				(copperpour not_allowed)
				(footprints allowed)
			)
			(placement
				(enabled no)
				(sheetname "")
			)
			(fill
				(thermal_gap 0.5)
				(thermal_bridge_width 0.5)
				(island_removal_mode 0)
			)
			(polygon
				(pts
					(xy 18.706592 -116.891054) (xy 18.706592 -117.399054) (xy 18.325592 -117.399054) (xy 18.325592 -116.891054)
				)
			)
		)
	)
)
